# S9S_MB_2U (Grand Teton) — schematic netlist excerpt (pin names and nets, part order shuffled) for the footprints in the layout excerpt that follows; sources: Cadence DE-HDL packaged netlist, KiCad conversion of 03242023_DA0F0TMBIJ0_F0T_Motherboard_J_brd_V01_OCP.brd

PR1850  Q_RES  1K 1% EMPTY  pkg 0402LF  page 263 : A = GND ; B = FM_PCH_P1V8_AUX_EN_R
C2291  Q_CAP  0.1UF 6.3V 10% X6S  pkg C0201  page 169 : A = USB3_PCH_RX_BUF_C_DP<4> ; B = USB3_PCH_RX_BUF_DP<4>
R45  Q_RES  35.7K 1% CHIP  pkg 0402LF  page 101 : A = PD_CHB_CPU1_DIMM2_SAA ; B = GND

(kicad_pcb
	(version 20260206)
	(generator "pcbnew")
	(generator_version "10.0")
	(general
		(thickness 1.6)
		(legacy_teardrops no)
	)
	(paper "A4")
	(title_block
		(title "03242023_DA0F0TMBIJ0_F0T_Motherboard_J_brd_V01_OCP.brd")
		(comment 1 "Grand Teton / footprints 5785-5787 of 6105")
	)
	(layers
		(0 "F.Cu" signal "TOP")
		(4 "In1.Cu" signal "GND")
		(6 "In2.Cu" signal "IN1")
		(8 "In3.Cu" signal "GND1")
		(10 "In4.Cu" signal "IN2")
		(12 "In5.Cu" signal "GND2")
		(14 "In6.Cu" signal "IN3")
		(16 "In7.Cu" signal "GND3")
		(18 "In8.Cu" signal "VCC")
		(20 "In9.Cu" signal "VCC1")
		(22 "In10.Cu" signal "GND4")
		(24 "In11.Cu" signal "IN4")
		(26 "In12.Cu" signal "GND5")
		(28 "In13.Cu" signal "IN5")
		(30 "In14.Cu" signal "GND6")
		(32 "In15.Cu" signal "IN6")
		(34 "In16.Cu" signal "GND7")
		(2 "B.Cu" signal "BOTTOM")
		(9 "F.Adhes" user "F.Adhesive")
		(11 "B.Adhes" user "B.Adhesive")
		(13 "F.Paste" user "Package Geometry/Pastemask Top")
		(15 "B.Paste" user "Package Geometry/Pastemask Bottom")
		(5 "F.SilkS" user "Ref Des/Silkscreen Top")
		(7 "B.SilkS" user "Ref Des/Silkscreen Bottom")
		(1 "F.Mask" user "Board Geometry/Soldermask Top")
		(3 "B.Mask" user "Board Geometry/Soldermask Bottom")
		(17 "Dwgs.User" user "User.Drawings")
		(19 "Cmts.User" user "User.Comments")
		(21 "Eco1.User" user "User.Eco1")
		(23 "Eco2.User" user "User.Eco2")
		(25 "Edge.Cuts" user "Board Geometry/Outline")
		(27 "Margin" user)
		(31 "F.CrtYd" user "Package Geometry/Place Bound Top")
		(29 "B.CrtYd" user "Package Geometry/Place Bound Bottom")
		(35 "F.Fab" user "Ref Des/Assembly Top")
		(33 "B.Fab" user "Ref Des/Assembly Bottom")
	)
	(footprint ""
		(layer "B.Cu")
		(at 47.689516 -319.009522)
		(property "Reference" "R45"
			(at 0 0 0)
			(layer "B.SilkS")
			(hide yes)
			(effects
				(font
					(size 1.27 1.27)
				)
				(justify mirror)
			)
		)
		(property "Value" ""
			(at 0 0 0)
			(layer "B.Fab")
			(effects
				(font
					(size 1.27 1.27)
				)
				(justify mirror)
			)
		)
		(duplicate_pad_numbers_are_jumpers no)
		(fp_line
			(start -0.7874 -0.4064)
			(end -0.7874 0.4064)
			(stroke
				(width 0.1524)
				(type default)
			)
			(layer "B.SilkS")
		)
		(fp_line
			(start -0.7874 0.4064)
			(end 0.7874 0.4064)
			(stroke
				(width 0.1524)
				(type default)
			)
			(layer "B.SilkS")
		)
		(fp_line
			(start 0.7874 -0.4064)
			(end -0.7874 -0.4064)
			(stroke
				(width 0.1524)
				(type default)
			)
			(layer "B.SilkS")
		)
		(fp_line
			(start 0.7874 0.4064)
			(end 0.7874 -0.4064)
			(stroke
				(width 0.1524)
				(type default)
			)
			(layer "B.SilkS")
		)
		(fp_line
			(start -0.67945 -0.3048)
			(end -0.67945 0.3048)
			(stroke
				(width 0.1)
				(type default)
			)
			(layer "B.Fab")
		)
		(fp_line
			(start -0.67945 0.3048)
			(end -0.120396 0.3048)
			(stroke
				(width 0.1)
				(type default)
			)
			(layer "B.Fab")
		)
		(fp_line
			(start -0.12065 -0.3048)
			(end -0.67945 -0.3048)
			(stroke
				(width 0.1)
				(type default)
			)
			(layer "B.Fab")
		)
		(fp_line
			(start -0.12065 -0.2794)
			(end -0.12065 -0.3048)
			(stroke
				(width 0.1)
				(type default)
			)
			(layer "B.Fab")
		)
		(fp_line
			(start -0.120396 0.2794)
			(end 0.12065 0.2794)
			(stroke
				(width 0.1)
				(type default)
			)
			(layer "B.Fab")
		)
		(fp_line
			(start -0.120396 0.3048)
			(end -0.120396 0.2794)
			(stroke
				(width 0.1)
				(type default)
			)
			(layer "B.Fab")
		)
		(fp_line
			(start 0.12065 -0.305054)
			(end 0.12065 -0.2794)
			(stroke
				(width 0.1)
				(type default)
			)
			(layer "B.Fab")
		)
		(fp_line
			(start 0.12065 -0.2794)
			(end -0.12065 -0.2794)
			(stroke
				(width 0.1)
				(type default)
			)
			(layer "B.Fab")
		)
		(fp_line
			(start 0.12065 0.2794)
			(end 0.12065 0.3048)
			(stroke
				(width 0.1)
				(type default)
			)
			(layer "B.Fab")
		)
		(fp_line
			(start 0.12065 0.3048)
			(end 0.67945 0.3048)
			(stroke
				(width 0.1)
				(type default)
			)
			(layer "B.Fab")
		)
		(fp_line
			(start 0.67945 -0.305054)
			(end 0.12065 -0.305054)
			(stroke
				(width 0.1)
				(type default)
			)
			(layer "B.Fab")
		)
		(fp_line
			(start 0.67945 0.3048)
			(end 0.67945 -0.305054)
			(stroke
				(width 0.1)
				(type default)
			)
			(layer "B.Fab")
		)
		(pad "1" smd circle
			(at 0.40005 0 180)
			(size 0 0)
			(layers "B.Cu" "B.Mask" "B.Paste")
			(net "PD_CHB_CPU1_DIMM2_SAA")
		)
		(pad "2" smd circle
			(at -0.40005 0 180)
			(size 0 0)
			(layers "B.Cu" "B.Mask" "B.Paste")
			(net "GND")
		)
	)
	(footprint ""
		(layer "B.Cu")
		(at 123.57862 -28.265628)
		(property "Reference" "C2291"
			(at 0 0 0)
			(layer "B.SilkS")
			(hide yes)
			(effects
				(font
					(size 1.27 1.27)
				)
				(justify mirror)
			)
		)
		(property "Value" ""
			(at 0 0 0)
			(layer "B.Fab")
			(effects
				(font
					(size 1.27 1.27)
				)
				(justify mirror)
			)
		)
		(duplicate_pad_numbers_are_jumpers no)
		(fp_line
			(start -0.299974 -0.150114)
			(end -0.299974 0.150114)
			(stroke
				(width 0.1)
				(type default)
			)
			(layer "B.Fab")
		)
		(fp_line
			(start -0.299974 0.150114)
			(end 0.299974 0.150114)
			(stroke
				(width 0.1)
				(type default)
			)
			(layer "B.Fab")
		)
		(fp_line
			(start 0.299974 -0.150114)
			(end -0.299974 -0.150114)
			(stroke
				(width 0.1)
				(type default)
			)
			(layer "B.Fab")
		)
		(fp_line
			(start 0.299974 0.150114)
			(end 0.299974 -0.150114)
			(stroke
				(width 0.1)
				(type default)
			)
			(layer "B.Fab")
		)
		(pad "1" smd rect
			(at 0.2667 0 180)
			(size 0.3048 0.381)
			(layers "B.Cu" "B.Mask" "B.Paste")
			(net "USB3_PCH_RX_BUF_C_DP<4>")
		)
		(pad "2" smd rect
			(at -0.2667 0 180)
			(size 0.3048 0.381)
			(layers "B.Cu" "B.Mask" "B.Paste")
			(net "USB3_PCH_RX_BUF_DP<4>")
		)
	)
	(footprint ""
		(layer "B.Cu")
		(at 385.1402 -79.428848)
		(property "Reference" "PR1850"
			(at 0 0 0)
			(layer "B.SilkS")
			(hide yes)
			(effects
				(font
					(size 1.27 1.27)
				)
				(justify mirror)
			)
		)
		(property "Value" ""
			(at 0 0 0)
			(layer "B.Fab")
			(effects
				(font
					(size 1.27 1.27)
				)
				(justify mirror)
			)
		)
		(duplicate_pad_numbers_are_jumpers no)
		(fp_line
			(start -0.7874 -0.4064)
			(end -0.7874 0.4064)
			(stroke
				(width 0.1524)
				(type default)
			)
			(layer "B.SilkS")
		)
		(fp_line
			(start -0.7874 0.4064)
			(end 0.7874 0.4064)
			(stroke
				(width 0.1524)
				(type default)
			)
			(layer "B.SilkS")
		)
		(fp_line
			(start 0.7874 -0.4064)
			(end -0.7874 -0.4064)
			(stroke
				(width 0.1524)
				(type default)
			)
			(layer "B.SilkS")
		)
		(fp_line
			(start 0.7874 0.4064)
			(end 0.7874 -0.4064)
			(stroke
				(width 0.1524)
				(type default)
			)
			(layer "B.SilkS")
		)
		(fp_line
			(start -0.67945 -0.3048)
			(end -0.67945 0.3048)
			(stroke
				(width 0.1)
				(type default)
			)
			(layer "B.Fab")
		)
		(fp_line
			(start -0.67945 0.3048)
			(end -0.120396 0.3048)
			(stroke
				(width 0.1)
				(type default)
			)
			(layer "B.Fab")
		)
		(fp_line
			(start -0.12065 -0.3048)
			(end -0.67945 -0.3048)
			(stroke
				(width 0.1)
				(type default)
			)
			(layer "B.Fab")
		)
		(fp_line
			(start -0.12065 -0.2794)
			(end -0.12065 -0.3048)
			(stroke
				(width 0.1)
				(type default)
			)
			(layer "B.Fab")
		)
		(fp_line
			(start -0.120396 0.2794)
			(end 0.12065 0.2794)
			(stroke
				(width 0.1)
				(type default)
			)
			(layer "B.Fab")
		)
		(fp_line
			(start -0.120396 0.3048)
			(end -0.120396 0.2794)
			(stroke
				(width 0.1)
				(type default)
			)
			(layer "B.Fab")
		)
		(fp_line
			(start 0.12065 -0.305054)
			(end 0.12065 -0.2794)
			(stroke
				(width 0.1)
				(type default)
			)
			(layer "B.Fab")
		)
		(fp_line
			(start 0.12065 -0.2794)
			(end -0.12065 -0.2794)
			(stroke
				(width 0.1)
				(type default)
			)
			(layer "B.Fab")
		)
		(fp_line
			(start 0.12065 0.2794)
			(end 0.12065 0.3048)
			(stroke
				(width 0.1)
				(type default)
			)
			(layer "B.Fab")
		)
		(fp_line
			(start 0.12065 0.3048)
			(end 0.67945 0.3048)
			(stroke
				(width 0.1)
				(type default)
			)
			(layer "B.Fab")
		)
		(fp_line
			(start 0.67945 -0.305054)
			(end 0.12065 -0.305054)
			(stroke
				(width 0.1)
				(type default)
			)
			(layer "B.Fab")
		)
		(fp_line
			(start 0.67945 0.3048)
			(end 0.67945 -0.305054)
			(stroke
				(width 0.1)
				(type default)
			)
			(layer "B.Fab")
		)
		(pad "1" smd circle
			(at 0.40005 0 180)
			(size 0 0)
			(layers "B.Cu" "B.Mask" "B.Paste")
			(net "GND")
		)
		(pad "2" smd circle
			(at -0.40005 0 180)
			(size 0 0)
			(layers "B.Cu" "B.Mask" "B.Paste")
			(net "FM_PCH_P1V8_AUX_EN_R")
		)
	)
)
